FILE_TYPE = CONNECTIVITY;
{Allegro Design Entry HDL 17.2-2016 S081 (4005846) 1/11/2022}
"PAGE_NUMBER" = 49;
0"NC";
1"GMI_CPU1_G0_CPU0_G2_TX_DN<0:15>";
2"GMI_CPU1_G0_CPU0_G2_TX_DP<0:15>";
3"GMI_CPU1_G1_CPU0_G3_TX_DP<0:15>";
4"GMI_CPU0_G2_CPU1_G0_TX_DN<0:15>";
5"GMI_CPU0_G2_CPU1_G0_TX_DP<0:15>";
6"GMI_CPU0_G3_CPU1_G1_TX_DP<0:15>";
7"GMI_CPU0_G3_CPU1_G1_TX_DN<0:15>";
8"GMI_CPU1_G1_CPU0_G3_TX_DN<0:15>";
9"GMI_CPU0_G3_CPU1_G1_TX_DN<8>";
10"GMI_CPU0_G3_CPU1_G1_TX_DN<9>";
11"GMI_CPU0_G3_CPU1_G1_TX_DN<10>";
12"GMI_CPU0_G3_CPU1_G1_TX_DP<8>";
13"GMI_CPU0_G3_CPU1_G1_TX_DN<11>";
14"GMI_CPU0_G3_CPU1_G1_TX_DP<9>";
15"GMI_CPU0_G3_CPU1_G1_TX_DN<12>";
16"GMI_CPU0_G3_CPU1_G1_TX_DP<10>";
17"GMI_CPU0_G3_CPU1_G1_TX_DN<13>";
18"GMI_CPU0_G3_CPU1_G1_TX_DP<11>";
19"GMI_CPU0_G3_CPU1_G1_TX_DN<14>";
20"GMI_CPU0_G3_CPU1_G1_TX_DP<12>";
21"GMI_CPU0_G3_CPU1_G1_TX_DN<15>";
22"GMI_CPU0_G3_CPU1_G1_TX_DP<13>";
23"GMI_CPU0_G3_CPU1_G1_TX_DP<14>";
24"GMI_CPU0_G3_CPU1_G1_TX_DP<15>";
25"GMI_CPU0_G3_CPU1_G1_TX_DN<7>";
26"GMI_CPU0_G3_CPU1_G1_TX_DN<6>";
27"GMI_CPU0_G3_CPU1_G1_TX_DN<5>";
28"GMI_CPU0_G3_CPU1_G1_TX_DN<4>";
29"GMI_CPU0_G3_CPU1_G1_TX_DN<3>";
30"GMI_CPU0_G3_CPU1_G1_TX_DN<2>";
31"GMI_CPU0_G3_CPU1_G1_TX_DN<1>";
32"GMI_CPU0_G3_CPU1_G1_TX_DN<0>";
33"GMI_CPU0_G3_CPU1_G1_TX_DP<7>";
34"GMI_CPU0_G3_CPU1_G1_TX_DP<6>";
35"GMI_CPU0_G3_CPU1_G1_TX_DP<5>";
36"GMI_CPU0_G3_CPU1_G1_TX_DP<4>";
37"GMI_CPU0_G3_CPU1_G1_TX_DP<3>";
38"GMI_CPU0_G3_CPU1_G1_TX_DP<2>";
39"GMI_CPU0_G3_CPU1_G1_TX_DP<1>";
40"GMI_CPU0_G3_CPU1_G1_TX_DP<0>";
41"GMI_CPU0_G2_CPU1_G0_TX_DP<0>";
42"GMI_CPU0_G2_CPU1_G0_TX_DP<1>";
43"GMI_CPU0_G2_CPU1_G0_TX_DP<2>";
44"GMI_CPU0_G2_CPU1_G0_TX_DP<3>";
45"GMI_CPU0_G2_CPU1_G0_TX_DP<4>";
46"GMI_CPU0_G2_CPU1_G0_TX_DP<5>";
47"GMI_CPU0_G2_CPU1_G0_TX_DP<6>";
48"GMI_CPU0_G2_CPU1_G0_TX_DP<7>";
49"GMI_CPU0_G2_CPU1_G0_TX_DP<8>";
50"GMI_CPU0_G2_CPU1_G0_TX_DP<9>";
51"GMI_CPU0_G2_CPU1_G0_TX_DP<10>";
52"GMI_CPU0_G2_CPU1_G0_TX_DP<11>";
53"GMI_CPU0_G2_CPU1_G0_TX_DP<12>";
54"GMI_CPU0_G2_CPU1_G0_TX_DP<13>";
55"GMI_CPU0_G2_CPU1_G0_TX_DP<14>";
56"GMI_CPU0_G2_CPU1_G0_TX_DP<15>";
57"GMI_CPU0_G2_CPU1_G0_TX_DN<0>";
58"GMI_CPU0_G2_CPU1_G0_TX_DN<1>";
59"GMI_CPU0_G2_CPU1_G0_TX_DN<2>";
60"GMI_CPU0_G2_CPU1_G0_TX_DN<3>";
61"GMI_CPU0_G2_CPU1_G0_TX_DN<4>";
62"GMI_CPU0_G2_CPU1_G0_TX_DN<5>";
63"GMI_CPU0_G2_CPU1_G0_TX_DN<6>";
64"GMI_CPU0_G2_CPU1_G0_TX_DN<7>";
65"GMI_CPU0_G2_CPU1_G0_TX_DN<8>";
66"GMI_CPU0_G2_CPU1_G0_TX_DN<9>";
67"GMI_CPU0_G2_CPU1_G0_TX_DN<10>";
68"GMI_CPU0_G2_CPU1_G0_TX_DN<11>";
69"GMI_CPU0_G2_CPU1_G0_TX_DN<12>";
70"GMI_CPU0_G2_CPU1_G0_TX_DN<13>";
71"GMI_CPU0_G2_CPU1_G0_TX_DN<14>";
72"GMI_CPU0_G2_CPU1_G0_TX_DN<15>";
73"GMI_CPU1_G1_CPU0_G3_TX_DP<0>";
74"GMI_CPU1_G1_CPU0_G3_TX_DP<5>";
75"GMI_CPU1_G1_CPU0_G3_TX_DP<4>";
76"GMI_CPU1_G1_CPU0_G3_TX_DP<3>";
77"GMI_CPU1_G1_CPU0_G3_TX_DP<2>";
78"GMI_CPU1_G1_CPU0_G3_TX_DP<1>";
79"GMI_CPU1_G1_CPU0_G3_TX_DN<5>";
80"GMI_CPU1_G1_CPU0_G3_TX_DN<4>";
81"GMI_CPU1_G1_CPU0_G3_TX_DN<3>";
82"GMI_CPU1_G1_CPU0_G3_TX_DN<2>";
83"GMI_CPU1_G1_CPU0_G3_TX_DN<1>";
84"GMI_CPU1_G1_CPU0_G3_TX_DN<0>";
85"GMI_CPU1_G1_CPU0_G3_TX_DP<8>";
86"GMI_CPU1_G1_CPU0_G3_TX_DP<9>";
87"GMI_CPU1_G1_CPU0_G3_TX_DP<10>";
88"GMI_CPU1_G1_CPU0_G3_TX_DP<7>";
89"GMI_CPU1_G1_CPU0_G3_TX_DP<6>";
90"GMI_CPU1_G1_CPU0_G3_TX_DP<11>";
91"GMI_CPU1_G1_CPU0_G3_TX_DP<12>";
92"GMI_CPU1_G1_CPU0_G3_TX_DP<13>";
93"GMI_CPU1_G1_CPU0_G3_TX_DP<14>";
94"GMI_CPU1_G1_CPU0_G3_TX_DP<15>";
95"GMI_CPU1_G1_CPU0_G3_TX_DN<8>";
96"GMI_CPU1_G1_CPU0_G3_TX_DN<9>";
97"GMI_CPU1_G1_CPU0_G3_TX_DN<10>";
98"GMI_CPU1_G1_CPU0_G3_TX_DN<11>";
99"GMI_CPU1_G1_CPU0_G3_TX_DN<12>";
100"GMI_CPU1_G1_CPU0_G3_TX_DN<13>";
101"GMI_CPU1_G1_CPU0_G3_TX_DN<14>";
102"GMI_CPU1_G1_CPU0_G3_TX_DN<15>";
103"GMI_CPU1_G1_CPU0_G3_TX_DN<7>";
104"GMI_CPU1_G1_CPU0_G3_TX_DN<6>";
105"GMI_CPU1_G0_CPU0_G2_TX_DP<0>";
106"GMI_CPU1_G0_CPU0_G2_TX_DP<1>";
107"GMI_CPU1_G0_CPU0_G2_TX_DP<2>";
108"GMI_CPU1_G0_CPU0_G2_TX_DP<3>";
109"GMI_CPU1_G0_CPU0_G2_TX_DP<4>";
110"GMI_CPU1_G0_CPU0_G2_TX_DP<5>";
111"GMI_CPU1_G0_CPU0_G2_TX_DP<6>";
112"GMI_CPU1_G0_CPU0_G2_TX_DP<7>";
113"GMI_CPU1_G0_CPU0_G2_TX_DP<8>";
114"GMI_CPU1_G0_CPU0_G2_TX_DP<9>";
115"GMI_CPU1_G0_CPU0_G2_TX_DP<10>";
116"GMI_CPU1_G0_CPU0_G2_TX_DP<11>";
117"GMI_CPU1_G0_CPU0_G2_TX_DP<12>";
118"GMI_CPU1_G0_CPU0_G2_TX_DP<13>";
119"GMI_CPU1_G0_CPU0_G2_TX_DP<14>";
120"GMI_CPU1_G0_CPU0_G2_TX_DP<15>";
121"GMI_CPU1_G0_CPU0_G2_TX_DN<0>";
122"GMI_CPU1_G0_CPU0_G2_TX_DN<1>";
123"GMI_CPU1_G0_CPU0_G2_TX_DN<2>";
124"GMI_CPU1_G0_CPU0_G2_TX_DN<3>";
125"GMI_CPU1_G0_CPU0_G2_TX_DN<4>";
126"GMI_CPU1_G0_CPU0_G2_TX_DN<5>";
127"GMI_CPU1_G0_CPU0_G2_TX_DN<6>";
128"GMI_CPU1_G0_CPU0_G2_TX_DN<7>";
129"GMI_CPU1_G0_CPU0_G2_TX_DN<8>";
130"GMI_CPU1_G0_CPU0_G2_TX_DN<9>";
131"GMI_CPU1_G0_CPU0_G2_TX_DN<10>";
132"GMI_CPU1_G0_CPU0_G2_TX_DN<11>";
133"GMI_CPU1_G0_CPU0_G2_TX_DN<12>";
134"GMI_CPU1_G0_CPU0_G2_TX_DN<13>";
135"GMI_CPU1_G0_CPU0_G2_TX_DN<14>";
136"GMI_CPU1_G0_CPU0_G2_TX_DN<15>";
%"GENOA_SP5"
"11","(-4775,5000)","0","pure_quanta","I213";
;
LOCATION"U26"
$SEC"11"
CDS_SEC"11"
PART_TYPE"SMLF"
MATERIAL"IO"
VALUE"SOCKET6096_13568-001"
PART_NUMBER"DGA^6000030"
CDS_LIB"pure_quanta"
NEEDS_NO_SIZE"TRUE"
CDS_LMAN_SYM_OUTLINE"-1100,950,1100,-950";
"G0_TXP15"
$PN"AE52"105;
"G0_TXP14"
$PN"AC52"106;
"G0_TXP13"
$PN"AG52"107;
"G0_TXP12"
$PN"AE49"108;
"G0_TXP11"
$PN"AC49"109;
"G0_TXP10"
$PN"AG49"110;
"G0_TXP9"
$PN"AE46"111;
"G0_TXP8"
$PN"AC46"112;
"G0_TXP7"
$PN"AG46"113;
"G0_TXP6"
$PN"AE43"114;
"G0_TXP5"
$PN"AC43"115;
"G0_TXP4"
$PN"AA43"116;
"G0_TXP3"
$PN"AG43"117;
"G0_TXP2"
$PN"AB40"118;
"G0_TXP1"
$PN"AD40"119;
"G0_TXP0"
$PN"AF40"120;
"G0_TXN15"
$PN"AE53"121;
"G0_TXN14"
$PN"AC53"122;
"G0_TXN13"
$PN"AG53"123;
"G0_TXN12"
$PN"AE50"124;
"G0_TXN11"
$PN"AC50"125;
"G0_TXN10"
$PN"AG50"126;
"G0_TXN9"
$PN"AE47"127;
"G0_TXN8"
$PN"AC47"128;
"G0_TXN7"
$PN"AG47"129;
"G0_TXN6"
$PN"AE44"130;
"G0_TXN5"
$PN"AC44"131;
"G0_TXN4"
$PN"AA44"132;
"G0_TXN3"
$PN"AG44"133;
"G0_TXN2"
$PN"AB41"134;
"G0_TXN1"
$PN"AD41"135;
"G0_TXN0"
$PN"AF41"136;
"G0_RXP15"
$PN"N53"41;
"G0_RXP14"
$PN"J53"42;
"G0_RXP13"
$PN"G53"43;
"G0_RXP12"
$PN"L53"44;
"G0_RXP11"
$PN"J50"45;
"G0_RXP10"
$PN"G50"46;
"G0_RXP9"
$PN"L50"47;
"G0_RXP8"
$PN"J47"48;
"G0_RXP7"
$PN"G47"49;
"G0_RXP6"
$PN"L47"50;
"G0_RXP5"
$PN"J44"51;
"G0_RXP4"
$PN"G44"52;
"G0_RXP3"
$PN"L44"53;
"G0_RXP2"
$PN"H41"54;
"G0_RXP1"
$PN"K41"55;
"G0_RXP0"
$PN"M41"56;
"G0_RXN15"
$PN"N52"57;
"G0_RXN14"
$PN"J52"58;
"G0_RXN13"
$PN"G52"59;
"G0_RXN12"
$PN"L52"60;
"G0_RXN11"
$PN"J49"61;
"G0_RXN10"
$PN"G49"62;
"G0_RXN9"
$PN"L49"63;
"G0_RXN8"
$PN"J46"64;
"G0_RXN7"
$PN"G46"65;
"G0_RXN6"
$PN"L46"66;
"G0_RXN5"
$PN"J43"67;
"G0_RXN4"
$PN"G43"68;
"G0_RXN3"
$PN"L43"69;
"G0_RXN2"
$PN"H40"70;
"G0_RXN1"
$PN"K40"71;
"G0_RXN0"
$PN"M40"72;
%"GENOA_SP5"
"12","(-4750,2275)","0","pure_quanta","I214";
;
LOCATION"U26"
$SEC"12"
CDS_SEC"12"
PART_TYPE"SMLF"
MATERIAL"IO"
VALUE"SOCKET6096_13568-001"
PART_NUMBER"DGA^6000030"
CDS_LIB"pure_quanta"
NEEDS_NO_SIZE"TRUE"
CDS_LMAN_SYM_OUTLINE"-1100,950,1100,-950";
"G1_RXN7"
$PN"N46"9;
"G1_RXN6"
$PN"U46"10;
"G1_RXN5"
$PN"R43"11;
"G1_RXP7"
$PN"N47"12;
"G1_TXN7"
$PN"AN47"95;
"G1_RXN4"
$PN"N43"13;
"G1_RXP6"
$PN"U47"14;
"G1_TXN6"
$PN"AL44"96;
"G1_RXN3"
$PN"U43"15;
"G1_RXP5"
$PN"R44"16;
"G1_TXN5"
$PN"AJ44"97;
"G1_TXP7"
$PN"AN46"85;
"G1_RXN2"
$PN"P40"17;
"G1_RXP4"
$PN"N44"18;
"G1_TXN4"
$PN"AN44"98;
"G1_TXP6"
$PN"AL43"86;
"G1_RXN1"
$PN"T40"19;
"G1_RXP3"
$PN"U44"20;
"G1_TXN3"
$PN"AK41"99;
"G1_TXP5"
$PN"AJ43"87;
"G1_RXN0"
$PN"V40"21;
"G1_RXP2"
$PN"P41"22;
"G1_TXN2"
$PN"AH41"100;
"G1_TXP4"
$PN"AN43"90;
"G1_RXP1"
$PN"T41"23;
"G1_TXN1"
$PN"AM41"101;
"G1_TXP3"
$PN"AK40"91;
"G1_RXP0"
$PN"V41"24;
"G1_TXN0"
$PN"AP41"102;
"G1_TXP2"
$PN"AH40"92;
"G1_TXP1"
$PN"AM40"93;
"G1_TXP0"
$PN"AP40"94;
"G1_RXN8"
$PN"R46"25;
"G1_RXN9"
$PN"W49"26;
"G1_RXN10"
$PN"N49"27;
"G1_RXN11"
$PN"R49"28;
"G1_RXN12"
$PN"U49"29;
"G1_RXN13"
$PN"W52"30;
"G1_RXN14"
$PN"R52"31;
"G1_RXN15"
$PN"U52"32;
"G1_RXP8"
$PN"R47"33;
"G1_RXP9"
$PN"W50"34;
"G1_RXP10"
$PN"N50"35;
"G1_RXP11"
$PN"R50"36;
"G1_RXP12"
$PN"U50"37;
"G1_RXP13"
$PN"W53"38;
"G1_RXP14"
$PN"R53"39;
"G1_RXP15"
$PN"U53"40;
"G1_TXN8"
$PN"AJ47"103;
"G1_TXN9"
$PN"AL47"104;
"G1_TXN10"
$PN"AN50"79;
"G1_TXN11"
$PN"AJ50"80;
"G1_TXN12"
$PN"AL50"81;
"G1_TXN13"
$PN"AN53"82;
"G1_TXN14"
$PN"AJ53"83;
"G1_TXN15"
$PN"AL53"84;
"G1_TXP8"
$PN"AJ46"88;
"G1_TXP9"
$PN"AL46"89;
"G1_TXP10"
$PN"AN49"74;
"G1_TXP11"
$PN"AJ49"75;
"G1_TXP12"
$PN"AL49"76;
"G1_TXP13"
$PN"AN52"77;
"G1_TXP14"
$PN"AJ52"78;
"G1_TXP15"
$PN"AL52"73;
%"TAP"
"6","(-3100,5650)","2","mstr_standard","I235";
;
BOM_COST"IO_SLOT"
CDS_LIB"mstr_standard"
BODY_TYPE"PLUMBING"
HDL_TAP"TRUE"
ROOM"RISER1";
"B \NAC \NWC"2;
"S \NAC"
BN"14"119;
%"TAP"
"6","(-3100,5750)","2","mstr_standard","I236";
;
BOM_COST"IO_SLOT"
CDS_LIB"mstr_standard"
BODY_TYPE"PLUMBING"
HDL_TAP"TRUE"
ROOM"RISER1";
"B \NAC \NWC"2;
"S \NAC"
BN"15"120;
%"TAP"
"6","(-3100,5550)","2","standard","I240";
;
BOM_COST"IO_SLOT"
CDS_LIB"standard"
BODY_TYPE"PLUMBING"
HDL_TAP"TRUE"
ROOM"RISER1";
"B \NAC \NWC"2;
"S \NAC"
BN"13"118;
%"TAP"
"6","(-3100,5450)","2","standard","I241";
;
BOM_COST"IO_SLOT"
CDS_LIB"standard"
BODY_TYPE"PLUMBING"
HDL_TAP"TRUE"
ROOM"RISER1";
"B \NAC \NWC"2;
"S \NAC"
BN"12"117;
%"TAP"
"6","(-3100,5350)","2","standard","I244";
;
BOM_COST"IO_SLOT"
CDS_LIB"standard"
BODY_TYPE"PLUMBING"
HDL_TAP"TRUE"
ROOM"RISER1";
"B \NAC \NWC"2;
"S \NAC"
BN"11"116;
%"TAP"
"6","(-3100,5250)","2","standard","I245";
;
BOM_COST"IO_SLOT"
CDS_LIB"standard"
BODY_TYPE"PLUMBING"
HDL_TAP"TRUE"
ROOM"RISER1";
"B \NAC \NWC"2;
"S \NAC"
BN"10"115;
%"TAP"
"6","(-3100,5150)","2","standard","I246";
;
BOM_COST"IO_SLOT"
CDS_LIB"standard"
BODY_TYPE"PLUMBING"
HDL_TAP"TRUE"
ROOM"RISER1";
"B \NAC \NWC"2;
"S \NAC"
BN"9"114;
%"TAP"
"6","(-3100,5050)","2","standard","I250";
;
BOM_COST"IO_SLOT"
CDS_LIB"standard"
BODY_TYPE"PLUMBING"
HDL_TAP"TRUE"
ROOM"RISER1";
"B \NAC \NWC"2;
"S \NAC"
BN"8"113;
%"TAP"
"6","(-3100,4950)","2","standard","I251";
;
BOM_COST"IO_SLOT"
CDS_LIB"standard"
BODY_TYPE"PLUMBING"
HDL_TAP"TRUE"
ROOM"RISER1";
"B \NAC \NWC"2;
"S \NAC"
BN"7"112;
%"TAP"
"6","(-3100,4850)","2","standard","I254";
;
BOM_COST"IO_SLOT"
CDS_LIB"standard"
BODY_TYPE"PLUMBING"
HDL_TAP"TRUE"
ROOM"RISER1";
"B \NAC \NWC"2;
"S \NAC"
BN"6"111;
%"TAP"
"6","(-3100,4750)","2","standard","I255";
;
BOM_COST"IO_SLOT"
CDS_LIB"standard"
BODY_TYPE"PLUMBING"
HDL_TAP"TRUE"
ROOM"RISER1";
"B \NAC \NWC"2;
"S \NAC"
BN"5"110;
%"TAP"
"6","(-3100,4650)","2","standard","I256";
;
BOM_COST"IO_SLOT"
CDS_LIB"standard"
BODY_TYPE"PLUMBING"
HDL_TAP"TRUE"
ROOM"RISER1";
"B \NAC \NWC"2;
"S \NAC"
BN"4"109;
%"TAP"
"6","(-3100,4550)","2","standard","I260";
;
BOM_COST"IO_SLOT"
CDS_LIB"standard"
BODY_TYPE"PLUMBING"
HDL_TAP"TRUE"
ROOM"RISER1";
"B \NAC \NWC"2;
"S \NAC"
BN"3"108;
%"TAP"
"6","(-3100,4450)","2","standard","I261";
;
BOM_COST"IO_SLOT"
CDS_LIB"standard"
BODY_TYPE"PLUMBING"
HDL_TAP"TRUE"
ROOM"RISER1";
"B \NAC \NWC"2;
"S \NAC"
BN"2"107;
%"TAP"
"6","(-3100,4350)","2","standard","I264";
;
BOM_COST"IO_SLOT"
CDS_LIB"standard"
BODY_TYPE"PLUMBING"
HDL_TAP"TRUE"
ROOM"RISER1";
"B \NAC \NWC"2;
"S \NAC"
BN"1"106;
%"TAP"
"6","(-3100,4250)","2","standard","I265";
;
BOM_COST"IO_SLOT"
CDS_LIB"standard"
BODY_TYPE"PLUMBING"
HDL_TAP"TRUE"
ROOM"RISER1";
"B \NAC \NWC"2;
"S \NAC"
BN"0"105;
%"TAP"
"6","(-3075,2925)","2","mstr_standard","I270";
;
CDS_LIB"mstr_standard"
BOM_COST"IO_SLOT"
BODY_TYPE"PLUMBING"
HDL_TAP"TRUE"
ROOM"RISER1";
"B \NAC \NWC"3;
"S \NAC"
BN"14"93;
%"TAP"
"6","(-3075,2825)","2","standard","I271";
;
CDS_LIB"standard"
BOM_COST"IO_SLOT"
BODY_TYPE"PLUMBING"
HDL_TAP"TRUE"
ROOM"RISER1";
"B \NAC \NWC"3;
"S \NAC"
BN"13"92;
%"TAP"
"6","(-3075,3025)","2","mstr_standard","I272";
;
CDS_LIB"mstr_standard"
BOM_COST"IO_SLOT"
BODY_TYPE"PLUMBING"
HDL_TAP"TRUE"
ROOM"RISER1";
"B \NAC \NWC"3;
"S \NAC"
BN"15"94;
%"TAP"
"6","(-3075,2725)","2","standard","I276";
;
CDS_LIB"standard"
BOM_COST"IO_SLOT"
BODY_TYPE"PLUMBING"
HDL_TAP"TRUE"
ROOM"RISER1";
"B \NAC \NWC"3;
"S \NAC"
BN"12"91;
%"TAP"
"6","(-3075,2625)","2","standard","I277";
;
CDS_LIB"standard"
BOM_COST"IO_SLOT"
BODY_TYPE"PLUMBING"
HDL_TAP"TRUE"
ROOM"RISER1";
"B \NAC \NWC"3;
"S \NAC"
BN"11"90;
%"TAP"
"6","(-3075,2425)","2","standard","I280";
;
CDS_LIB"standard"
BOM_COST"IO_SLOT"
BODY_TYPE"PLUMBING"
HDL_TAP"TRUE"
ROOM"RISER1";
"B \NAC \NWC"3;
"S \NAC"
BN"9"86;
%"TAP"
"6","(-3075,2325)","2","standard","I281";
;
CDS_LIB"standard"
BOM_COST"IO_SLOT"
BODY_TYPE"PLUMBING"
HDL_TAP"TRUE"
ROOM"RISER1";
"B \NAC \NWC"3;
"S \NAC"
BN"8"85;
%"TAP"
"6","(-3075,2525)","2","standard","I282";
;
CDS_LIB"standard"
BOM_COST"IO_SLOT"
BODY_TYPE"PLUMBING"
HDL_TAP"TRUE"
ROOM"RISER1";
"B \NAC \NWC"3;
"S \NAC"
BN"10"87;
%"TAP"
"6","(-3075,2225)","2","standard","I286";
;
CDS_LIB"standard"
BOM_COST"IO_SLOT"
BODY_TYPE"PLUMBING"
HDL_TAP"TRUE"
ROOM"RISER1";
"B \NAC \NWC"3;
"S \NAC"
BN"7"88;
%"TAP"
"6","(-3075,2125)","2","standard","I287";
;
CDS_LIB"standard"
BOM_COST"IO_SLOT"
BODY_TYPE"PLUMBING"
HDL_TAP"TRUE"
ROOM"RISER1";
"B \NAC \NWC"3;
"S \NAC"
BN"6"89;
%"TAP"
"6","(-3075,1925)","2","standard","I290";
;
CDS_LIB"standard"
BOM_COST"IO_SLOT"
BODY_TYPE"PLUMBING"
HDL_TAP"TRUE"
ROOM"RISER1";
"B \NAC \NWC"3;
"S \NAC"
BN"4"75;
%"TAP"
"6","(-3075,1825)","2","standard","I291";
;
CDS_LIB"standard"
BOM_COST"IO_SLOT"
BODY_TYPE"PLUMBING"
HDL_TAP"TRUE"
ROOM"RISER1";
"B \NAC \NWC"3;
"S \NAC"
BN"3"76;
%"TAP"
"6","(-3075,2025)","2","standard","I292";
;
CDS_LIB"standard"
BOM_COST"IO_SLOT"
BODY_TYPE"PLUMBING"
HDL_TAP"TRUE"
ROOM"RISER1";
"B \NAC \NWC"3;
"S \NAC"
BN"5"74;
%"TAP"
"6","(-3075,1725)","2","standard","I296";
;
CDS_LIB"standard"
BOM_COST"IO_SLOT"
BODY_TYPE"PLUMBING"
HDL_TAP"TRUE"
ROOM"RISER1";
"B \NAC \NWC"3;
"S \NAC"
BN"2"77;
%"TAP"
"6","(-3075,1625)","2","standard","I297";
;
CDS_LIB"standard"
BOM_COST"IO_SLOT"
BODY_TYPE"PLUMBING"
HDL_TAP"TRUE"
ROOM"RISER1";
"B \NAC \NWC"3;
"S \NAC"
BN"1"78;
%"TAP"
"6","(-3075,1525)","2","standard","I298";
;
CDS_LIB"standard"
BOM_COST"IO_SLOT"
BODY_TYPE"PLUMBING"
HDL_TAP"TRUE"
ROOM"RISER1";
"B \NAC \NWC"3;
"S \NAC"
BN"0"73;
%"TAP"
"6","(-6525,5750)","0","mstr_standard","I300";
;
CDS_LIB"mstr_standard"
BODY_TYPE"PLUMBING"
HDL_TAP"TRUE";
"B \NAC \NWC"5;
"S \NAC"
BN"15"56;
%"TAP"
"6","(-6525,5650)","0","mstr_standard","I301";
;
CDS_LIB"mstr_standard"
BODY_TYPE"PLUMBING"
HDL_TAP"TRUE";
"B \NAC \NWC"5;
"S \NAC"
BN"14"55;
%"TAP"
"6","(-6525,5550)","0","mstr_standard","I303";
;
CDS_LIB"mstr_standard"
BODY_TYPE"PLUMBING"
HDL_TAP"TRUE";
"B \NAC \NWC"5;
"S \NAC"
BN"13"54;
%"TAP"
"6","(-6525,5450)","0","standard","I304";
;
CDS_LIB"standard"
BODY_TYPE"PLUMBING"
HDL_TAP"TRUE";
"B \NAC \NWC"5;
"S \NAC"
BN"12"53;
%"TAP"
"6","(-6525,5250)","0","standard","I308";
;
CDS_LIB"standard"
BODY_TYPE"PLUMBING"
HDL_TAP"TRUE";
"B \NAC \NWC"5;
"S \NAC"
BN"10"51;
%"TAP"
"6","(-6525,5350)","0","standard","I309";
;
CDS_LIB"standard"
BODY_TYPE"PLUMBING"
HDL_TAP"TRUE";
"B \NAC \NWC"5;
"S \NAC"
BN"11"52;
%"TAP"
"6","(-6525,5150)","0","standard","I310";
;
CDS_LIB"standard"
BODY_TYPE"PLUMBING"
HDL_TAP"TRUE";
"B \NAC \NWC"5;
"S \NAC"
BN"9"50;
%"TAP"
"6","(-6525,5050)","0","standard","I313";
;
CDS_LIB"standard"
BODY_TYPE"PLUMBING"
HDL_TAP"TRUE";
"B \NAC \NWC"5;
"S \NAC"
BN"8"49;
%"TAP"
"6","(-6525,4950)","0","standard","I314";
;
CDS_LIB"standard"
BODY_TYPE"PLUMBING"
HDL_TAP"TRUE";
"B \NAC \NWC"5;
"S \NAC"
BN"7"48;
%"TAP"
"6","(-6525,4850)","0","standard","I318";
;
CDS_LIB"standard"
BODY_TYPE"PLUMBING"
HDL_TAP"TRUE";
"B \NAC \NWC"5;
"S \NAC"
BN"6"47;
%"TAP"
"6","(-6525,4750)","0","standard","I319";
;
CDS_LIB"standard"
BODY_TYPE"PLUMBING"
HDL_TAP"TRUE";
"B \NAC \NWC"5;
"S \NAC"
BN"5"46;
%"TAP"
"6","(-6525,4650)","0","standard","I320";
;
CDS_LIB"standard"
BODY_TYPE"PLUMBING"
HDL_TAP"TRUE";
"B \NAC \NWC"5;
"S \NAC"
BN"4"45;
%"TAP"
"6","(-6525,4550)","0","standard","I323";
;
CDS_LIB"standard"
BODY_TYPE"PLUMBING"
HDL_TAP"TRUE";
"B \NAC \NWC"5;
"S \NAC"
BN"3"44;
%"TAP"
"6","(-6525,4450)","0","standard","I324";
;
CDS_LIB"standard"
BODY_TYPE"PLUMBING"
HDL_TAP"TRUE";
"B \NAC \NWC"5;
"S \NAC"
BN"2"43;
%"TAP"
"6","(-6525,4250)","0","standard","I328";
;
CDS_LIB"standard"
BODY_TYPE"PLUMBING"
HDL_TAP"TRUE";
"B \NAC \NWC"5;
"S \NAC"
BN"0"41;
%"TAP"
"6","(-6525,4350)","0","standard","I329";
;
CDS_LIB"standard"
BODY_TYPE"PLUMBING"
HDL_TAP"TRUE";
"B \NAC \NWC"5;
"S \NAC"
BN"1"42;
%"TAP"
"6","(-6500,3025)","0","mstr_standard","I334";
;
CDS_LIB"mstr_standard"
BODY_TYPE"PLUMBING"
HDL_TAP"TRUE";
"B \NAC \NWC"6;
"S \NAC"
BN"15"24;
%"TAP"
"6","(-6500,2925)","0","mstr_standard","I335";
;
CDS_LIB"mstr_standard"
BODY_TYPE"PLUMBING"
HDL_TAP"TRUE";
"B \NAC \NWC"6;
"S \NAC"
BN"14"23;
%"TAP"
"6","(-6500,2825)","0","mstr_standard","I336";
;
CDS_LIB"mstr_standard"
BODY_TYPE"PLUMBING"
HDL_TAP"TRUE";
"B \NAC \NWC"6;
"S \NAC"
BN"13"22;
%"TAP"
"6","(-6500,2725)","0","standard","I339";
;
CDS_LIB"standard"
BODY_TYPE"PLUMBING"
HDL_TAP"TRUE";
"B \NAC \NWC"6;
"S \NAC"
BN"12"20;
%"TAP"
"6","(-6500,2625)","0","standard","I340";
;
CDS_LIB"standard"
BODY_TYPE"PLUMBING"
HDL_TAP"TRUE";
"B \NAC \NWC"6;
"S \NAC"
BN"11"18;
%"TAP"
"6","(-6500,2525)","0","standard","I344";
;
CDS_LIB"standard"
BODY_TYPE"PLUMBING"
HDL_TAP"TRUE";
"B \NAC \NWC"6;
"S \NAC"
BN"10"16;
%"TAP"
"6","(-6500,2425)","0","standard","I345";
;
CDS_LIB"standard"
BODY_TYPE"PLUMBING"
HDL_TAP"TRUE";
"B \NAC \NWC"6;
"S \NAC"
BN"9"14;
%"TAP"
"6","(-6500,2325)","0","standard","I346";
;
CDS_LIB"standard"
BODY_TYPE"PLUMBING"
HDL_TAP"TRUE";
"B \NAC \NWC"6;
"S \NAC"
BN"8"12;
%"TAP"
"6","(-6500,2225)","0","standard","I349";
;
CDS_LIB"standard"
BODY_TYPE"PLUMBING"
HDL_TAP"TRUE";
"B \NAC \NWC"6;
"S \NAC"
BN"7"33;
%"TAP"
"6","(-6500,2125)","0","standard","I350";
;
CDS_LIB"standard"
BODY_TYPE"PLUMBING"
HDL_TAP"TRUE";
"B \NAC \NWC"6;
"S \NAC"
BN"6"34;
%"TAP"
"6","(-6500,2025)","0","standard","I356";
;
CDS_LIB"standard"
BODY_TYPE"PLUMBING"
HDL_TAP"TRUE";
"B \NAC \NWC"6;
"S \NAC"
BN"5"35;
%"TAP"
"6","(-6500,1925)","0","standard","I357";
;
CDS_LIB"standard"
BODY_TYPE"PLUMBING"
HDL_TAP"TRUE";
"B \NAC \NWC"6;
"S \NAC"
BN"4"36;
%"TAP"
"6","(-6500,1825)","0","standard","I358";
;
CDS_LIB"standard"
BODY_TYPE"PLUMBING"
HDL_TAP"TRUE";
"B \NAC \NWC"6;
"S \NAC"
BN"3"37;
%"TAP"
"6","(-6500,1725)","0","standard","I361";
;
CDS_LIB"standard"
BODY_TYPE"PLUMBING"
HDL_TAP"TRUE";
"B \NAC \NWC"6;
"S \NAC"
BN"2"38;
%"TAP"
"6","(-6500,1625)","0","standard","I362";
;
CDS_LIB"standard"
BODY_TYPE"PLUMBING"
HDL_TAP"TRUE";
"B \NAC \NWC"6;
"S \NAC"
BN"1"39;
%"TAP"
"6","(-6500,1525)","0","standard","I366";
;
CDS_LIB"standard"
BODY_TYPE"PLUMBING"
HDL_TAP"TRUE";
"B \NAC \NWC"6;
"S \NAC"
BN"0"40;
%"TAP"
"6","(-2950,5700)","2","mstr_standard","I437";
;
CDS_LIB"mstr_standard"
BOM_COST"IO_SLOT"
BODY_TYPE"PLUMBING"
HDL_TAP"TRUE"
ROOM"RISER1";
"B \NAC \NWC"1;
"S \NAC"
BN"15"136;
%"TAP"
"6","(-2950,5600)","2","mstr_standard","I438";
;
BOM_COST"IO_SLOT"
CDS_LIB"mstr_standard"
BODY_TYPE"PLUMBING"
HDL_TAP"TRUE"
ROOM"RISER1";
"B \NAC \NWC"1;
"S \NAC"
BN"14"135;
%"TAP"
"6","(-2950,5500)","2","standard","I439";
;
BOM_COST"IO_SLOT"
CDS_LIB"standard"
BODY_TYPE"PLUMBING"
HDL_TAP"TRUE"
ROOM"RISER1";
"B \NAC \NWC"1;
"S \NAC"
BN"13"134;
%"TAP"
"6","(-2950,5400)","2","standard","I440";
;
BOM_COST"IO_SLOT"
CDS_LIB"standard"
BODY_TYPE"PLUMBING"
HDL_TAP"TRUE"
ROOM"RISER1";
"B \NAC \NWC"1;
"S \NAC"
BN"12"133;
%"TAP"
"6","(-2950,5300)","2","standard","I441";
;
BOM_COST"IO_SLOT"
CDS_LIB"standard"
BODY_TYPE"PLUMBING"
HDL_TAP"TRUE"
ROOM"RISER1";
"B \NAC \NWC"1;
"S \NAC"
BN"11"132;
%"TAP"
"6","(-2950,5200)","2","standard","I442";
;
BOM_COST"IO_SLOT"
CDS_LIB"standard"
BODY_TYPE"PLUMBING"
HDL_TAP"TRUE"
ROOM"RISER1";
"B \NAC \NWC"1;
"S \NAC"
BN"10"131;
%"TAP"
"6","(-2950,5100)","2","standard","I443";
;
BOM_COST"IO_SLOT"
CDS_LIB"standard"
BODY_TYPE"PLUMBING"
HDL_TAP"TRUE"
ROOM"RISER1";
"B \NAC \NWC"1;
"S \NAC"
BN"9"130;
%"TAP"
"6","(-2950,5000)","2","standard","I444";
;
BOM_COST"IO_SLOT"
CDS_LIB"standard"
BODY_TYPE"PLUMBING"
HDL_TAP"TRUE"
ROOM"RISER1";
"B \NAC \NWC"1;
"S \NAC"
BN"8"129;
%"TAP"
"6","(-2950,4900)","2","standard","I445";
;
BOM_COST"IO_SLOT"
CDS_LIB"standard"
BODY_TYPE"PLUMBING"
HDL_TAP"TRUE"
ROOM"RISER1";
"B \NAC \NWC"1;
"S \NAC"
BN"7"128;
%"TAP"
"6","(-2950,4700)","2","standard","I446";
;
BOM_COST"IO_SLOT"
CDS_LIB"standard"
BODY_TYPE"PLUMBING"
HDL_TAP"TRUE"
ROOM"RISER1";
"B \NAC \NWC"1;
"S \NAC"
BN"5"126;
%"TAP"
"6","(-2950,4800)","2","standard","I447";
;
BOM_COST"IO_SLOT"
CDS_LIB"standard"
BODY_TYPE"PLUMBING"
HDL_TAP"TRUE"
ROOM"RISER1";
"B \NAC \NWC"1;
"S \NAC"
BN"6"127;
%"TAP"
"6","(-2950,4600)","2","standard","I448";
;
BOM_COST"IO_SLOT"
CDS_LIB"standard"
BODY_TYPE"PLUMBING"
HDL_TAP"TRUE"
ROOM"RISER1";
"B \NAC \NWC"1;
"S \NAC"
BN"4"125;
%"TAP"
"6","(-2950,4500)","2","standard","I449";
;
BOM_COST"IO_SLOT"
CDS_LIB"standard"
BODY_TYPE"PLUMBING"
HDL_TAP"TRUE"
ROOM"RISER1";
"B \NAC \NWC"1;
"S \NAC"
BN"3"124;
%"TAP"
"6","(-2950,4300)","2","standard","I450";
;
CDS_LIB"standard"
BOM_COST"IO_SLOT"
BODY_TYPE"PLUMBING"
HDL_TAP"TRUE"
ROOM"RISER1";
"B \NAC \NWC"1;
"S \NAC"
BN"1"122;
%"TAP"
"6","(-2950,4400)","2","standard","I451";
;
BOM_COST"IO_SLOT"
CDS_LIB"standard"
BODY_TYPE"PLUMBING"
HDL_TAP"TRUE"
ROOM"RISER1";
"B \NAC \NWC"1;
"S \NAC"
BN"2"123;
%"TAP"
"6","(-2950,4200)","2","standard","I452";
;
BOM_COST"IO_SLOT"
CDS_LIB"standard"
BODY_TYPE"PLUMBING"
HDL_TAP"TRUE"
ROOM"RISER1";
"B \NAC \NWC"1;
"S \NAC"
BN"0"121;
%"TAP"
"6","(-6675,5700)","0","mstr_standard","I453";
;
CDS_LIB"mstr_standard"
BODY_TYPE"PLUMBING"
HDL_TAP"TRUE";
"B \NAC \NWC"4;
"S \NAC"
BN"15"72;
%"TAP"
"6","(-6675,5600)","0","mstr_standard","I454";
;
CDS_LIB"mstr_standard"
BODY_TYPE"PLUMBING"
HDL_TAP"TRUE";
"B \NAC \NWC"4;
"S \NAC"
BN"14"71;
%"TAP"
"6","(-6675,5500)","0","standard","I455";
;
CDS_LIB"standard"
BODY_TYPE"PLUMBING"
HDL_TAP"TRUE";
"B \NAC \NWC"4;
"S \NAC"
BN"13"70;
%"TAP"
"6","(-6675,5400)","0","standard","I456";
;
CDS_LIB"standard"
BODY_TYPE"PLUMBING"
HDL_TAP"TRUE";
"B \NAC \NWC"4;
"S \NAC"
BN"12"69;
%"TAP"
"6","(-6675,5200)","0","standard","I457";
;
CDS_LIB"standard"
BODY_TYPE"PLUMBING"
HDL_TAP"TRUE";
"B \NAC \NWC"4;
"S \NAC"
BN"10"67;
%"TAP"
"6","(-6675,5300)","0","standard","I458";
;
CDS_LIB"standard"
BODY_TYPE"PLUMBING"
HDL_TAP"TRUE";
"B \NAC \NWC"4;
"S \NAC"
BN"11"68;
%"TAP"
"6","(-6675,5100)","0","standard","I459";
;
CDS_LIB"standard"
BODY_TYPE"PLUMBING"
HDL_TAP"TRUE";
"B \NAC \NWC"4;
"S \NAC"
BN"9"66;
%"TAP"
"6","(-6675,5000)","0","standard","I460";
;
CDS_LIB"standard"
BODY_TYPE"PLUMBING"
HDL_TAP"TRUE";
"B \NAC \NWC"4;
"S \NAC"
BN"8"65;
%"TAP"
"6","(-6675,4900)","0","standard","I461";
;
CDS_LIB"standard"
BODY_TYPE"PLUMBING"
HDL_TAP"TRUE";
"B \NAC \NWC"4;
"S \NAC"
BN"7"64;
%"TAP"
"6","(-6675,4800)","0","standard","I462";
;
CDS_LIB"standard"
BODY_TYPE"PLUMBING"
HDL_TAP"TRUE";
"B \NAC \NWC"4;
"S \NAC"
BN"6"63;
%"TAP"
"6","(-6675,4700)","0","standard","I463";
;
CDS_LIB"standard"
BODY_TYPE"PLUMBING"
HDL_TAP"TRUE";
"B \NAC \NWC"4;
"S \NAC"
BN"5"62;
%"TAP"
"6","(-6675,4600)","0","standard","I464";
;
CDS_LIB"standard"
BODY_TYPE"PLUMBING"
HDL_TAP"TRUE";
"B \NAC \NWC"4;
"S \NAC"
BN"4"61;
%"TAP"
"6","(-6675,4500)","0","standard","I465";
;
CDS_LIB"standard"
BODY_TYPE"PLUMBING"
HDL_TAP"TRUE";
"B \NAC \NWC"4;
"S \NAC"
BN"3"60;
%"TAP"
"6","(-6675,4400)","0","standard","I466";
;
CDS_LIB"standard"
BODY_TYPE"PLUMBING"
HDL_TAP"TRUE";
"B \NAC \NWC"4;
"S \NAC"
BN"2"59;
%"TAP"
"6","(-6675,4200)","0","standard","I467";
;
CDS_LIB"standard"
BODY_TYPE"PLUMBING"
HDL_TAP"TRUE";
"B \NAC \NWC"4;
"S \NAC"
BN"0"57;
%"TAP"
"6","(-6675,4300)","0","standard","I468";
;
CDS_LIB"standard"
BODY_TYPE"PLUMBING"
HDL_TAP"TRUE";
"B \NAC \NWC"4;
"S \NAC"
BN"1"58;
%"TAP"
"6","(-6650,2875)","0","mstr_standard","I470";
;
CDS_LIB"mstr_standard"
BODY_TYPE"PLUMBING"
HDL_TAP"TRUE";
"B \NAC \NWC"7;
"S \NAC"
BN"14"19;
%"TAP"
"6","(-6650,2975)","0","mstr_standard","I471";
;
CDS_LIB"mstr_standard"
BODY_TYPE"PLUMBING"
HDL_TAP"TRUE";
"B \NAC \NWC"7;
"S \NAC"
BN"15"21;
%"TAP"
"6","(-6650,2775)","0","standard","I472";
;
CDS_LIB"standard"
BODY_TYPE"PLUMBING"
HDL_TAP"TRUE";
"B \NAC \NWC"7;
"S \NAC"
BN"13"17;
%"TAP"
"6","(-6650,2675)","0","standard","I473";
;
CDS_LIB"standard"
BODY_TYPE"PLUMBING"
HDL_TAP"TRUE";
"B \NAC \NWC"7;
"S \NAC"
BN"12"15;
%"TAP"
"6","(-6650,2475)","0","standard","I474";
;
CDS_LIB"standard"
BODY_TYPE"PLUMBING"
HDL_TAP"TRUE";
"B \NAC \NWC"7;
"S \NAC"
BN"10"11;
%"TAP"
"6","(-6650,2575)","0","standard","I475";
;
CDS_LIB"standard"
BODY_TYPE"PLUMBING"
HDL_TAP"TRUE";
"B \NAC \NWC"7;
"S \NAC"
BN"11"13;
%"TAP"
"6","(-6650,2375)","0","standard","I476";
;
CDS_LIB"standard"
BODY_TYPE"PLUMBING"
HDL_TAP"TRUE";
"B \NAC \NWC"7;
"S \NAC"
BN"9"10;
%"TAP"
"6","(-6650,2275)","0","standard","I477";
;
CDS_LIB"standard"
BODY_TYPE"PLUMBING"
HDL_TAP"TRUE";
"B \NAC \NWC"7;
"S \NAC"
BN"8"9;
%"TAP"
"6","(-6650,2175)","0","standard","I478";
;
CDS_LIB"standard"
BODY_TYPE"PLUMBING"
HDL_TAP"TRUE";
"B \NAC \NWC"7;
"S \NAC"
BN"7"25;
%"TAP"
"6","(-6650,1975)","0","standard","I479";
;
CDS_LIB"standard"
BODY_TYPE"PLUMBING"
HDL_TAP"TRUE";
"B \NAC \NWC"7;
"S \NAC"
BN"5"27;
%"TAP"
"6","(-6650,2075)","0","standard","I480";
;
CDS_LIB"standard"
BODY_TYPE"PLUMBING"
HDL_TAP"TRUE";
"B \NAC \NWC"7;
"S \NAC"
BN"6"26;
%"TAP"
"6","(-6650,1875)","0","standard","I481";
;
CDS_LIB"standard"
BODY_TYPE"PLUMBING"
HDL_TAP"TRUE";
"B \NAC \NWC"7;
"S \NAC"
BN"4"28;
%"TAP"
"6","(-6650,1775)","0","standard","I482";
;
CDS_LIB"standard"
BODY_TYPE"PLUMBING"
HDL_TAP"TRUE";
"B \NAC \NWC"7;
"S \NAC"
BN"3"29;
%"TAP"
"6","(-6650,1675)","0","standard","I483";
;
CDS_LIB"standard"
BODY_TYPE"PLUMBING"
HDL_TAP"TRUE";
"B \NAC \NWC"7;
"S \NAC"
BN"2"30;
%"TAP"
"6","(-6650,1575)","0","standard","I484";
;
CDS_LIB"standard"
BODY_TYPE"PLUMBING"
HDL_TAP"TRUE";
"B \NAC \NWC"7;
"S \NAC"
BN"1"31;
%"TAP"
"6","(-6650,1475)","0","standard","I485";
;
CDS_LIB"standard"
BODY_TYPE"PLUMBING"
HDL_TAP"TRUE";
"B \NAC \NWC"7;
"S \NAC"
BN"0"32;
%"TAP"
"6","(-2925,2975)","2","mstr_standard","I488";
;
BOM_COST"IO_SLOT"
CDS_LIB"mstr_standard"
BODY_TYPE"PLUMBING"
HDL_TAP"TRUE"
ROOM"RISER1";
"B \NAC \NWC"8;
"S \NAC"
BN"15"102;
%"TAP"
"6","(-2925,2875)","2","mstr_standard","I489";
;
CDS_LIB"mstr_standard"
BOM_COST"IO_SLOT"
BODY_TYPE"PLUMBING"
HDL_TAP"TRUE"
ROOM"RISER1";
"B \NAC \NWC"8;
"S \NAC"
BN"14"101;
%"TAP"
"6","(-2925,2775)","2","standard","I490";
;
CDS_LIB"standard"
BOM_COST"IO_SLOT"
BODY_TYPE"PLUMBING"
HDL_TAP"TRUE"
ROOM"RISER1";
"B \NAC \NWC"8;
"S \NAC"
BN"13"100;
%"TAP"
"6","(-2925,2675)","2","standard","I491";
;
CDS_LIB"standard"
BOM_COST"IO_SLOT"
BODY_TYPE"PLUMBING"
HDL_TAP"TRUE"
ROOM"RISER1";
"B \NAC \NWC"8;
"S \NAC"
BN"12"99;
%"TAP"
"6","(-2925,2575)","2","standard","I492";
;
CDS_LIB"standard"
BOM_COST"IO_SLOT"
BODY_TYPE"PLUMBING"
HDL_TAP"TRUE"
ROOM"RISER1";
"B \NAC \NWC"8;
"S \NAC"
BN"11"98;
%"TAP"
"6","(-2925,2475)","2","standard","I493";
;
CDS_LIB"standard"
BOM_COST"IO_SLOT"
BODY_TYPE"PLUMBING"
HDL_TAP"TRUE"
ROOM"RISER1";
"B \NAC \NWC"8;
"S \NAC"
BN"10"97;
%"TAP"
"6","(-2925,2375)","2","standard","I494";
;
CDS_LIB"standard"
BOM_COST"IO_SLOT"
BODY_TYPE"PLUMBING"
HDL_TAP"TRUE"
ROOM"RISER1";
"B \NAC \NWC"8;
"S \NAC"
BN"9"96;
%"TAP"
"6","(-2925,2275)","2","standard","I495";
;
CDS_LIB"standard"
BOM_COST"IO_SLOT"
BODY_TYPE"PLUMBING"
HDL_TAP"TRUE"
ROOM"RISER1";
"B \NAC \NWC"8;
"S \NAC"
BN"8"95;
%"TAP"
"6","(-2925,2175)","2","standard","I496";
;
CDS_LIB"standard"
BOM_COST"IO_SLOT"
BODY_TYPE"PLUMBING"
HDL_TAP"TRUE"
ROOM"RISER1";
"B \NAC \NWC"8;
"S \NAC"
BN"7"103;
%"TAP"
"6","(-2925,1975)","2","standard","I497";
;
CDS_LIB"standard"
BOM_COST"IO_SLOT"
BODY_TYPE"PLUMBING"
HDL_TAP"TRUE"
ROOM"RISER1";
"B \NAC \NWC"8;
"S \NAC"
BN"5"79;
%"TAP"
"6","(-2925,2075)","2","standard","I498";
;
CDS_LIB"standard"
BOM_COST"IO_SLOT"
BODY_TYPE"PLUMBING"
HDL_TAP"TRUE"
ROOM"RISER1";
"B \NAC \NWC"8;
"S \NAC"
BN"6"104;
%"TAP"
"6","(-2925,1775)","2","standard","I499";
;
CDS_LIB"standard"
BOM_COST"IO_SLOT"
BODY_TYPE"PLUMBING"
HDL_TAP"TRUE"
ROOM"RISER1";
"B \NAC \NWC"8;
"S \NAC"
BN"3"81;
%"TAP"
"6","(-2925,1875)","2","standard","I500";
;
CDS_LIB"standard"
BOM_COST"IO_SLOT"
BODY_TYPE"PLUMBING"
HDL_TAP"TRUE"
ROOM"RISER1";
"B \NAC \NWC"8;
"S \NAC"
BN"4"80;
%"TAP"
"6","(-2925,1675)","2","standard","I501";
;
CDS_LIB"standard"
BOM_COST"IO_SLOT"
BODY_TYPE"PLUMBING"
HDL_TAP"TRUE"
ROOM"RISER1";
"B \NAC \NWC"8;
"S \NAC"
BN"2"82;
%"TAP"
"6","(-2925,1575)","2","standard","I502";
;
BOM_COST"IO_SLOT"
CDS_LIB"standard"
BODY_TYPE"PLUMBING"
HDL_TAP"TRUE"
ROOM"RISER1";
"B \NAC \NWC"8;
"S \NAC"
BN"1"83;
%"TAP"
"6","(-2925,1475)","2","standard","I503";
;
CDS_LIB"standard"
BOM_COST"IO_SLOT"
BODY_TYPE"PLUMBING"
HDL_TAP"TRUE"
ROOM"RISER1";
"B \NAC \NWC"8;
"S \NAC"
BN"0"84;
END.
